(kicad_pcb
	(version 20260206)
	(generator "pcbnew")
	(generator_version "10.0")
	(general
		(thickness 1.6)
		(legacy_teardrops no)
	)
	(paper "A4")
	(title_block
		(title "pdpb — Lightning_PDPB_BRD.brd")
		(comment 1 "Lightning (Wiwynn / Facebook NVMe JBOF) / footprints 851-858 of 1140")
	)
	(layers
		(0 "F.Cu" signal "TOP")
		(4 "In1.Cu" signal "L2GND")
		(6 "In2.Cu" signal "L3")
		(8 "In3.Cu" signal "L4VCC")
		(10 "In4.Cu" signal "L5VCC")
		(12 "In5.Cu" signal "L6")
		(14 "In6.Cu" signal "L7GND")
		(2 "B.Cu" signal "BOTTOM")
		(9 "F.Adhes" user "F.Adhesive")
		(11 "B.Adhes" user "B.Adhesive")
		(13 "F.Paste" user "Package Geometry/Pastemask Top")
		(15 "B.Paste" user "Package Geometry/Pastemask Bottom")
		(5 "F.SilkS" user "Ref Des/Silkscreen Top")
		(7 "B.SilkS" user "Ref Des/Silkscreen Bottom")
		(1 "F.Mask" user "Board Geometry/Soldermask Top")
		(3 "B.Mask" user "Board Geometry/Soldermask Bottom")
		(17 "Dwgs.User" user "User.Drawings")
		(19 "Cmts.User" user "User.Comments")
		(21 "Eco1.User" user "User.Eco1")
		(23 "Eco2.User" user "User.Eco2")
		(25 "Edge.Cuts" user "Board Geometry/Outline")
		(27 "Margin" user)
		(31 "F.CrtYd" user "Package Geometry/Place Bound Top")
		(29 "B.CrtYd" user "Package Geometry/Place Bound Bottom")
		(35 "F.Fab" user "Ref Des/Assembly Top")
		(33 "B.Fab" user "Ref Des/Assembly Bottom")
	)
	(footprint ""
		(layer "F.Cu")
		(at 46.609 -134.874 -90)
		(property "Reference" "R320"
			(at 0 0 270)
			(layer "F.SilkS")
			(hide yes)
			(effects
				(font
					(size 1.27 1.27)
				)
			)
		)
		(property "Value" "0R2J-2-GP"
			(at 0.064008 -3.993896 270)
			(unlocked yes)
			(layer "F.Fab")
			(hide yes)
			(effects
				(font
					(size 1.016 1.016)
					(thickness 0.1524)
				)
			)
		)
		(property "Device Type" "R402H16"
			(at 0.064008 -5.517896 270)
			(unlocked yes)
			(layer "F.Fab")
			(hide yes)
			(effects
				(font
					(size 1.016 1.016)
					(thickness 0.1524)
				)
			)
		)
		(duplicate_pad_numbers_are_jumpers no)
		(fp_line
			(start -0.508 -0.9398)
			(end -0.508 0.9398)
			(stroke
				(width 0.1524)
				(type default)
			)
			(layer "F.SilkS")
		)
		(fp_line
			(start 0.508 -0.9398)
			(end -0.508 -0.9398)
			(stroke
				(width 0.1524)
				(type default)
			)
			(layer "F.SilkS")
		)
		(fp_rect
			(start -0.508 0.9398)
			(end 0.508 -0.9398)
			(stroke
				(width 0)
				(type default)
			)
			(fill no)
			(layer "F.CrtYd")
		)
		(fp_rect
			(start -0.508 0.9398)
			(end 0.508 -0.9398)
			(stroke
				(width 0)
				(type default)
			)
			(fill no)
			(layer "F.Fab")
		)
		(pad "1" smd custom
			(at 0 -0.4445 270)
			(size 0.1397 0.1397)
			(layers "F.Cu" "F.Mask" "F.Paste")
			(net "I2C_B_SDA")
			(options
				(clearance outline)
				(anchor circle)
			)
			(primitives
				(gr_poly
					(pts
						(arc
							(start -0.1778 -0.2794)
							(mid -0.249642 -0.249642)
							(end -0.2794 -0.1778)
						)
						(arc
							(start -0.2794 0.1778)
							(mid -0.249642 0.249642)
							(end -0.1778 0.2794)
						)
						(arc
							(start 0.1778 0.2794)
							(mid 0.249642 0.249642)
							(end 0.2794 0.1778)
						)
						(arc
							(start 0.2794 -0.1778)
							(mid 0.249642 -0.249642)
							(end 0.1778 -0.2794)
						)
					)
					(width 0)
					(fill yes)
				)
			)
		)
		(pad "2" smd custom
			(at 0 0.4445 270)
			(size 0.1397 0.1397)
			(layers "F.Cu" "F.Mask" "F.Paste")
			(net "TMP1_SDA")
			(options
				(clearance outline)
				(anchor circle)
			)
			(primitives
				(gr_poly
					(pts
						(arc
							(start -0.1778 -0.2794)
							(mid -0.249642 -0.249642)
							(end -0.2794 -0.1778)
						)
						(arc
							(start -0.2794 0.1778)
							(mid -0.249642 0.249642)
							(end -0.1778 0.2794)
						)
						(arc
							(start 0.1778 0.2794)
							(mid 0.249642 0.249642)
							(end 0.2794 0.1778)
						)
						(arc
							(start 0.2794 -0.1778)
							(mid 0.249642 -0.249642)
							(end 0.1778 -0.2794)
						)
					)
					(width 0)
					(fill yes)
				)
			)
		)
	)
	(footprint ""
		(layer "F.Cu")
		(at 24.8158 -88.646 -90)
		(property "Reference" "R147"
			(at 0 0 270)
			(layer "F.SilkS")
			(hide yes)
			(effects
				(font
					(size 1.27 1.27)
				)
			)
		)
		(property "Value" "4K7R2J-2-GP"
			(at 0.064008 -3.993896 270)
			(unlocked yes)
			(layer "F.Fab")
			(hide yes)
			(effects
				(font
					(size 1.016 1.016)
					(thickness 0.1524)
				)
			)
		)
		(property "Device Type" "R402H16"
			(at 0.064008 -5.517896 270)
			(unlocked yes)
			(layer "F.Fab")
			(hide yes)
			(effects
				(font
					(size 1.016 1.016)
					(thickness 0.1524)
				)
			)
		)
		(duplicate_pad_numbers_are_jumpers no)
		(fp_line
			(start -0.508 -0.9398)
			(end -0.508 0.9398)
			(stroke
				(width 0.1524)
				(type default)
			)
			(layer "F.SilkS")
		)
		(fp_line
			(start 0.508 -0.9398)
			(end -0.508 -0.9398)
			(stroke
				(width 0.1524)
				(type default)
			)
			(layer "F.SilkS")
		)
		(fp_rect
			(start -0.508 0.9398)
			(end 0.508 -0.9398)
			(stroke
				(width 0)
				(type default)
			)
			(fill no)
			(layer "F.CrtYd")
		)
		(fp_rect
			(start -0.508 0.9398)
			(end 0.508 -0.9398)
			(stroke
				(width 0)
				(type default)
			)
			(fill no)
			(layer "F.Fab")
		)
		(pad "1" smd custom
			(at 0 -0.4445 270)
			(size 0.1397 0.1397)
			(layers "F.Cu" "F.Mask" "F.Paste")
			(net "P12V")
			(options
				(clearance outline)
				(anchor circle)
			)
			(primitives
				(gr_poly
					(pts
						(arc
							(start -0.1778 -0.2794)
							(mid -0.249642 -0.249642)
							(end -0.2794 -0.1778)
						)
						(arc
							(start -0.2794 0.1778)
							(mid -0.249642 0.249642)
							(end -0.1778 0.2794)
						)
						(arc
							(start 0.1778 0.2794)
							(mid 0.249642 0.249642)
							(end 0.2794 0.1778)
						)
						(arc
							(start 0.2794 -0.1778)
							(mid 0.249642 -0.249642)
							(end 0.1778 -0.2794)
						)
					)
					(width 0)
					(fill yes)
				)
			)
		)
		(pad "2" smd custom
			(at 0 0.4445 270)
			(size 0.1397 0.1397)
			(layers "F.Cu" "F.Mask" "F.Paste")
			(net "SW_SSD9_R")
			(options
				(clearance outline)
				(anchor circle)
			)
			(primitives
				(gr_poly
					(pts
						(arc
							(start -0.1778 -0.2794)
							(mid -0.249642 -0.249642)
							(end -0.2794 -0.1778)
						)
						(arc
							(start -0.2794 0.1778)
							(mid -0.249642 0.249642)
							(end -0.1778 0.2794)
						)
						(arc
							(start 0.1778 0.2794)
							(mid 0.249642 0.249642)
							(end 0.2794 0.1778)
						)
						(arc
							(start 0.2794 -0.1778)
							(mid 0.249642 -0.249642)
							(end 0.1778 -0.2794)
						)
					)
					(width 0)
					(fill yes)
				)
			)
		)
	)
	(footprint ""
		(layer "F.Cu")
		(at 78.994 -310.896 90)
		(property "Reference" "FB7"
			(at 0 0 90)
			(layer "F.SilkS")
			(hide yes)
			(effects
				(font
					(size 1.27 1.27)
				)
			)
		)
		(property "Value" "BLM21PG331SN1D-2-GP"
			(at 0 -4.2418 90)
			(unlocked yes)
			(layer "F.Fab")
			(hide yes)
			(effects
				(font
					(size 1.016 1.016)
					(thickness 0.1524)
				)
			)
		)
		(property "Device Type" "L805H42"
			(at 0 -5.7912 90)
			(unlocked yes)
			(layer "F.Fab")
			(hide yes)
			(effects
				(font
					(size 1.016 1.016)
					(thickness 0.1524)
				)
			)
		)
		(duplicate_pad_numbers_are_jumpers no)
		(fp_line
			(start 0.889 -1.7018)
			(end 0.889 1.7018)
			(stroke
				(width 0.1524)
				(type default)
			)
			(layer "F.SilkS")
		)
		(fp_line
			(start -0.889 -1.7018)
			(end 0.889 -1.7018)
			(stroke
				(width 0.1524)
				(type default)
			)
			(layer "F.SilkS")
		)
		(fp_line
			(start 0.889 1.7018)
			(end -0.889 1.7018)
			(stroke
				(width 0.1524)
				(type default)
			)
			(layer "F.SilkS")
		)
		(fp_line
			(start -0.889 1.7018)
			(end -0.889 -1.7018)
			(stroke
				(width 0.1524)
				(type default)
			)
			(layer "F.SilkS")
		)
		(fp_rect
			(start -0.9652 1.778)
			(end 0.9652 -1.778)
			(stroke
				(width 0)
				(type default)
			)
			(fill no)
			(layer "F.CrtYd")
		)
		(fp_rect
			(start -0.9652 1.778)
			(end 0.9652 -1.778)
			(stroke
				(width 0)
				(type default)
			)
			(fill no)
			(layer "F.Fab")
		)
		(pad "1" smd rect
			(at 0 -0.9652 90)
			(size 1.397 1.143)
			(layers "F.Cu" "F.Mask" "F.Paste")
			(net "P3V3")
		)
		(pad "2" smd rect
			(at 0 0.9652 90)
			(size 1.397 1.143)
			(layers "F.Cu" "F.Mask" "F.Paste")
			(net "VDD_DIFF_2")
		)
	)
	(footprint ""
		(layer "F.Cu")
		(at 95.885 -26.162)
		(property "Reference" "R9758"
			(at 0 0 0)
			(layer "F.SilkS")
			(hide yes)
			(effects
				(font
					(size 1.27 1.27)
				)
			)
		)
		(property "Value" "1KR2J-1-GP"
			(at 0.064008 -3.993896 0)
			(unlocked yes)
			(layer "F.Fab")
			(hide yes)
			(effects
				(font
					(size 1.016 1.016)
					(thickness 0.1524)
				)
			)
		)
		(property "Device Type" "R402H16"
			(at 0.064008 -5.517896 0)
			(unlocked yes)
			(layer "F.Fab")
			(hide yes)
			(effects
				(font
					(size 1.016 1.016)
					(thickness 0.1524)
				)
			)
		)
		(duplicate_pad_numbers_are_jumpers no)
		(fp_line
			(start -0.508 -0.9398)
			(end -0.508 0.9398)
			(stroke
				(width 0.1524)
				(type default)
			)
			(layer "F.SilkS")
		)
		(fp_line
			(start 0.508 -0.9398)
			(end -0.508 -0.9398)
			(stroke
				(width 0.1524)
				(type default)
			)
			(layer "F.SilkS")
		)
		(fp_rect
			(start -0.508 0.9398)
			(end 0.508 -0.9398)
			(stroke
				(width 0)
				(type default)
			)
			(fill no)
			(layer "F.CrtYd")
		)
		(fp_rect
			(start -0.508 0.9398)
			(end 0.508 -0.9398)
			(stroke
				(width 0)
				(type default)
			)
			(fill no)
			(layer "F.Fab")
		)
		(pad "1" smd custom
			(at 0 -0.4445)
			(size 0.1397 0.1397)
			(layers "F.Cu" "F.Mask" "F.Paste")
			(net "P3V3_SENSE")
			(options
				(clearance outline)
				(anchor circle)
			)
			(primitives
				(gr_poly
					(pts
						(arc
							(start -0.1778 -0.2794)
							(mid -0.249642 -0.249642)
							(end -0.2794 -0.1778)
						)
						(arc
							(start -0.2794 0.1778)
							(mid -0.249642 0.249642)
							(end -0.1778 0.2794)
						)
						(arc
							(start 0.1778 0.2794)
							(mid 0.249642 0.249642)
							(end 0.2794 0.1778)
						)
						(arc
							(start 0.2794 -0.1778)
							(mid 0.249642 -0.249642)
							(end 0.1778 -0.2794)
						)
					)
					(width 0)
					(fill yes)
				)
			)
		)
		(pad "2" smd custom
			(at 0 0.4445)
			(size 0.1397 0.1397)
			(layers "F.Cu" "F.Mask" "F.Paste")
			(net "GND")
			(options
				(clearance outline)
				(anchor circle)
			)
			(primitives
				(gr_poly
					(pts
						(arc
							(start -0.1778 -0.2794)
							(mid -0.249642 -0.249642)
							(end -0.2794 -0.1778)
						)
						(arc
							(start -0.2794 0.1778)
							(mid -0.249642 0.249642)
							(end -0.1778 0.2794)
						)
						(arc
							(start 0.1778 0.2794)
							(mid 0.249642 0.249642)
							(end 0.2794 0.1778)
						)
						(arc
							(start 0.2794 -0.1778)
							(mid 0.249642 -0.249642)
							(end 0.1778 -0.2794)
						)
					)
					(width 0)
					(fill yes)
				)
			)
		)
	)
	(footprint ""
		(layer "F.Cu")
		(at 210.185 -432.816)
		(property "Reference" "PC1285"
			(at 0 0 0)
			(layer "F.SilkS")
			(hide yes)
			(effects
				(font
					(size 1.27 1.27)
				)
			)
		)
		(property "Value" "SC47U10V5MX-GP-U"
			(at -0.0762 -2.9972 0)
			(unlocked yes)
			(layer "F.Fab")
			(hide yes)
			(effects
				(font
					(size 1.016 1.016)
					(thickness 0.1524)
				)
			)
		)
		(property "Device Type" "C805H62"
			(at -0.0762 -4.5212 0)
			(unlocked yes)
			(layer "F.Fab")
			(hide yes)
			(effects
				(font
					(size 1.016 1.016)
					(thickness 0.1524)
				)
			)
		)
		(duplicate_pad_numbers_are_jumpers no)
		(fp_line
			(start 0.635 0)
			(end -0.635 0)
			(stroke
				(width 0.508)
				(type default)
			)
			(layer "F.SilkS")
		)
		(fp_rect
			(start -0.6223 1.0033)
			(end 0.6223 -1.0033)
			(stroke
				(width 0)
				(type default)
			)
			(fill no)
			(layer "F.CrtYd")
		)
		(fp_poly
			(pts
				(xy -0.9652 1.778) (xy -0.9652 -1.778) (xy 0.9652 -1.778) (xy 0.9652 0.39116) (xy 0.6223 0.39116)
				(xy 0.6223 -1.0033) (xy -0.6223 -1.0033) (xy -0.6223 1.0033) (xy 0.6223 1.0033) (xy 0.6223 0.3937)
				(xy 0.9652 0.3937) (xy 0.9652 1.778)
			)
			(stroke
				(width 0)
				(type default)
			)
			(fill no)
			(layer "F.CrtYd")
		)
		(fp_rect
			(start -0.9652 1.778)
			(end 0.9652 -1.778)
			(stroke
				(width 0)
				(type default)
			)
			(fill no)
			(layer "F.Fab")
		)
		(pad "1" smd rect
			(at 0 -0.9652)
			(size 1.397 1.143)
			(layers "F.Cu" "F.Mask" "F.Paste")
			(net "P3V3_OUT")
		)
		(pad "2" smd rect
			(at 0 0.9652)
			(size 1.397 1.143)
			(layers "F.Cu" "F.Mask" "F.Paste")
			(net "GND")
		)
	)
	(footprint ""
		(layer "F.Cu")
		(at 42.974768 -454.835768 -90)
		(property "Reference" "R9937"
			(at 0 0 270)
			(layer "F.SilkS")
			(hide yes)
			(effects
				(font
					(size 1.27 1.27)
				)
			)
		)
		(property "Value" "4K7R2J-2-GP"
			(at 0.064008 -3.993896 270)
			(unlocked yes)
			(layer "F.Fab")
			(hide yes)
			(effects
				(font
					(size 1.016 1.016)
					(thickness 0.1524)
				)
			)
		)
		(property "Device Type" "R402H16"
			(at 0.064008 -5.517896 270)
			(unlocked yes)
			(layer "F.Fab")
			(hide yes)
			(effects
				(font
					(size 1.016 1.016)
					(thickness 0.1524)
				)
			)
		)
		(duplicate_pad_numbers_are_jumpers no)
		(fp_line
			(start -0.508 -0.9398)
			(end -0.508 0.9398)
			(stroke
				(width 0.1524)
				(type default)
			)
			(layer "F.SilkS")
		)
		(fp_line
			(start 0.508 -0.9398)
			(end -0.508 -0.9398)
			(stroke
				(width 0.1524)
				(type default)
			)
			(layer "F.SilkS")
		)
		(fp_rect
			(start -0.508 0.9398)
			(end 0.508 -0.9398)
			(stroke
				(width 0)
				(type default)
			)
			(fill no)
			(layer "F.CrtYd")
		)
		(fp_rect
			(start -0.508 0.9398)
			(end 0.508 -0.9398)
			(stroke
				(width 0)
				(type default)
			)
			(fill no)
			(layer "F.Fab")
		)
		(pad "1" smd custom
			(at 0 -0.4445 270)
			(size 0.1397 0.1397)
			(layers "F.Cu" "F.Mask" "F.Paste")
			(net "P3V3")
			(options
				(clearance outline)
				(anchor circle)
			)
			(primitives
				(gr_poly
					(pts
						(arc
							(start -0.1778 -0.2794)
							(mid -0.249642 -0.249642)
							(end -0.2794 -0.1778)
						)
						(arc
							(start -0.2794 0.1778)
							(mid -0.249642 0.249642)
							(end -0.1778 0.2794)
						)
						(arc
							(start 0.1778 0.2794)
							(mid 0.249642 0.249642)
							(end 0.2794 0.1778)
						)
						(arc
							(start 0.2794 -0.1778)
							(mid 0.249642 -0.249642)
							(end 0.1778 -0.2794)
						)
					)
					(width 0)
					(fill yes)
				)
			)
		)
		(pad "2" smd custom
			(at 0 0.4445 270)
			(size 0.1397 0.1397)
			(layers "F.Cu" "F.Mask" "F.Paste")
			(net "ATTN_LED_DR5_MOS_N")
			(options
				(clearance outline)
				(anchor circle)
			)
			(primitives
				(gr_poly
					(pts
						(arc
							(start -0.1778 -0.2794)
							(mid -0.249642 -0.249642)
							(end -0.2794 -0.1778)
						)
						(arc
							(start -0.2794 0.1778)
							(mid -0.249642 0.249642)
							(end -0.1778 0.2794)
						)
						(arc
							(start 0.1778 0.2794)
							(mid 0.249642 0.249642)
							(end 0.2794 0.1778)
						)
						(arc
							(start 0.2794 -0.1778)
							(mid 0.249642 -0.249642)
							(end 0.1778 -0.2794)
						)
					)
					(width 0)
					(fill yes)
				)
			)
		)
	)
	(footprint ""
		(layer "F.Cu")
		(at 99.06 -89.535 90)
		(property "Reference" "C9374"
			(at 0 0 90)
			(layer "F.SilkS")
			(hide yes)
			(effects
				(font
					(size 1.27 1.27)
				)
			)
		)
		(property "Value" "SC1KP50V2KX-1GP"
			(at 1.1811 -2.7051 90)
			(unlocked yes)
			(layer "F.Fab")
			(hide yes)
			(effects
				(font
					(size 1.016 1.016)
					(thickness 0.1524)
				)
			)
		)
		(property "Device Type" "C402H22"
			(at 1.1811 -4.2291 90)
			(unlocked yes)
			(layer "F.Fab")
			(hide yes)
			(effects
				(font
					(size 1.016 1.016)
					(thickness 0.1524)
				)
			)
		)
		(duplicate_pad_numbers_are_jumpers no)
		(fp_rect
			(start -0.4318 0.9525)
			(end 0.4318 -0.9525)
			(stroke
				(width 0)
				(type default)
			)
			(fill no)
			(layer "F.CrtYd")
		)
		(fp_rect
			(start -0.4318 0.9525)
			(end 0.4318 -0.9525)
			(stroke
				(width 0)
				(type default)
			)
			(fill no)
			(layer "F.Fab")
		)
		(pad "1" smd custom
			(at 0 -0.4445 90)
			(size 0.1524 0.1524)
			(layers "F.Cu" "F.Mask" "F.Paste")
			(net "SSD14_CLK0_OE_R_N")
			(options
				(clearance outline)
				(anchor circle)
			)
			(primitives
				(gr_poly
					(pts
						(arc
							(start 0.3048 -0.2032)
							(mid 0.275042 -0.275042)
							(end 0.2032 -0.3048)
						)
						(arc
							(start -0.2032 -0.3048)
							(mid -0.275042 -0.275042)
							(end -0.3048 -0.2032)
						)
						(arc
							(start -0.3048 0.2032)
							(mid -0.275042 0.275042)
							(end -0.2032 0.3048)
						)
						(arc
							(start 0.2032 0.3048)
							(mid 0.275042 0.275042)
							(end 0.3048 0.2032)
						)
					)
					(width 0)
					(fill yes)
				)
			)
		)
		(pad "2" smd custom
			(at 0 0.4445 90)
			(size 0.1524 0.1524)
			(layers "F.Cu" "F.Mask" "F.Paste")
			(net "GND")
			(options
				(clearance outline)
				(anchor circle)
			)
			(primitives
				(gr_poly
					(pts
						(arc
							(start 0.3048 -0.2032)
							(mid 0.275042 -0.275042)
							(end 0.2032 -0.3048)
						)
						(arc
							(start -0.2032 -0.3048)
							(mid -0.275042 -0.275042)
							(end -0.3048 -0.2032)
						)
						(arc
							(start -0.3048 0.2032)
							(mid -0.275042 0.275042)
							(end -0.2032 0.3048)
						)
						(arc
							(start 0.2032 0.3048)
							(mid 0.275042 0.275042)
							(end 0.3048 0.2032)
						)
					)
					(width 0)
					(fill yes)
				)
			)
		)
	)
	(footprint ""
		(layer "F.Cu")
		(at 102.616 -307.721 90)
		(property "Reference" "R9075"
			(at 0 0 90)
			(layer "F.SilkS")
			(hide yes)
			(effects
				(font
					(size 1.27 1.27)
				)
			)
		)
		(property "Value" "27R2F-GP"
			(at 0.064008 -3.993896 90)
			(unlocked yes)
			(layer "F.Fab")
			(hide yes)
			(effects
				(font
					(size 1.016 1.016)
					(thickness 0.1524)
				)
			)
		)
		(property "Device Type" "R402H16"
			(at 0.064008 -5.517896 90)
			(unlocked yes)
			(layer "F.Fab")
			(hide yes)
			(effects
				(font
					(size 1.016 1.016)
					(thickness 0.1524)
				)
			)
		)
		(duplicate_pad_numbers_are_jumpers no)
		(fp_line
			(start 0.508 -0.9398)
			(end -0.508 -0.9398)
			(stroke
				(width 0.1524)
				(type default)
			)
			(layer "F.SilkS")
		)
		(fp_line
			(start -0.508 -0.9398)
			(end -0.508 0.9398)
			(stroke
				(width 0.1524)
				(type default)
			)
			(layer "F.SilkS")
		)
		(fp_rect
			(start -0.508 0.9398)
			(end 0.508 -0.9398)
			(stroke
				(width 0)
				(type default)
			)
			(fill no)
			(layer "F.CrtYd")
		)
		(fp_rect
			(start -0.508 0.9398)
			(end 0.508 -0.9398)
			(stroke
				(width 0)
				(type default)
			)
			(fill no)
			(layer "F.Fab")
		)
		(pad "1" smd custom
			(at 0 -0.4445 90)
			(size 0.1397 0.1397)
			(layers "F.Cu" "F.Mask" "F.Paste")
			(net "PE_CLK_100M_DR1_2_R_N")
			(options
				(clearance outline)
				(anchor circle)
			)
			(primitives
				(gr_poly
					(pts
						(arc
							(start -0.1778 -0.2794)
							(mid -0.249642 -0.249642)
							(end -0.2794 -0.1778)
						)
						(arc
							(start -0.2794 0.1778)
							(mid -0.249642 0.249642)
							(end -0.1778 0.2794)
						)
						(arc
							(start 0.1778 0.2794)
							(mid 0.249642 0.249642)
							(end 0.2794 0.1778)
						)
						(arc
							(start 0.2794 -0.1778)
							(mid 0.249642 -0.249642)
							(end 0.1778 -0.2794)
						)
					)
					(width 0)
					(fill yes)
				)
			)
		)
		(pad "2" smd custom
			(at 0 0.4445 90)
			(size 0.1397 0.1397)
			(layers "F.Cu" "F.Mask" "F.Paste")
			(net "PE_CLK100M_DR1_2_N")
			(options
				(clearance outline)
				(anchor circle)
			)
			(primitives
				(gr_poly
					(pts
						(arc
							(start -0.1778 -0.2794)
							(mid -0.249642 -0.249642)
							(end -0.2794 -0.1778)
						)
						(arc
							(start -0.2794 0.1778)
							(mid -0.249642 0.249642)
							(end -0.1778 0.2794)
						)
						(arc
							(start 0.1778 0.2794)
							(mid 0.249642 0.249642)
							(end 0.2794 0.1778)
						)
						(arc
							(start 0.2794 -0.1778)
							(mid 0.249642 -0.249642)
							(end 0.1778 -0.2794)
						)
					)
					(width 0)
					(fill yes)
				)
			)
		)
	)
)
